(kicad_pcb
	(version 20260206)
	(generator "pcbnew")
	(generator_version "10.0")
	(general
		(thickness 1.6)
		(legacy_teardrops no)
	)
	(paper "A4")
	(title_block
		(title "01162023_DA0F0TEBIF0_F0T_Expander_BD_F_brd_V02_OCP.brd")
		(comment 1 "Grand Teton / footprints 4982-4988 of 9728")
	)
	(layers
		(0 "F.Cu" signal "TOP")
		(4 "In1.Cu" signal "GND")
		(6 "In2.Cu" signal "VCC")
		(8 "In3.Cu" signal "VCC1")
		(10 "In4.Cu" signal "GND1")
		(12 "In5.Cu" signal "IN1")
		(14 "In6.Cu" signal "GND2")
		(16 "In7.Cu" signal "IN2")
		(18 "In8.Cu" signal "GND3")
		(20 "In9.Cu" signal "IN3")
		(22 "In10.Cu" signal "GND4")
		(24 "In11.Cu" signal "IN4")
		(26 "In12.Cu" signal "GND5")
		(28 "In13.Cu" signal "IN5")
		(30 "In14.Cu" signal "GND6")
		(32 "In15.Cu" signal "IN6")
		(34 "In16.Cu" signal "GND7")
		(2 "B.Cu" signal "BOTTOM")
		(9 "F.Adhes" user "F.Adhesive")
		(11 "B.Adhes" user "B.Adhesive")
		(13 "F.Paste" user "Package Geometry/Pastemask Top")
		(15 "B.Paste" user "Package Geometry/Pastemask Bottom")
		(5 "F.SilkS" user "Ref Des/Silkscreen Top")
		(7 "B.SilkS" user "Ref Des/Silkscreen Bottom")
		(1 "F.Mask" user "Board Geometry/Soldermask Top")
		(3 "B.Mask" user "Board Geometry/Soldermask Bottom")
		(17 "Dwgs.User" user "User.Drawings")
		(19 "Cmts.User" user "User.Comments")
		(21 "Eco1.User" user "User.Eco1")
		(23 "Eco2.User" user "User.Eco2")
		(25 "Edge.Cuts" user "Board Geometry/Outline")
		(27 "Margin" user)
		(31 "F.CrtYd" user "Package Geometry/Place Bound Top")
		(29 "B.CrtYd" user "Package Geometry/Place Bound Bottom")
		(35 "F.Fab" user "Ref Des/Assembly Top")
		(33 "B.Fab" user "Ref Des/Assembly Bottom")
	)
	(footprint ""
		(layer "F.Cu")
		(at 448.947032 -54.3941)
		(property "Reference" "PU45"
			(at -1.964436 2.902204 0)
			(unlocked yes)
			(layer "F.SilkS")
			(effects
				(font
					(size 0.7874 0.5842)
					(thickness 0.1524)
				)
				(justify left)
			)
		)
		(property "Value" ""
			(at 0 0 0)
			(layer "F.Fab")
			(effects
				(font
					(size 1.27 1.27)
				)
			)
		)
		(duplicate_pad_numbers_are_jumpers no)
		(fp_line
			(start -1.943608 -1.549908)
			(end 1.943608 -1.549908)
			(stroke
				(width 0.1524)
				(type default)
			)
			(layer "F.SilkS")
		)
		(fp_line
			(start -1.943608 1.549908)
			(end -1.943608 -1.549908)
			(stroke
				(width 0.1524)
				(type default)
			)
			(layer "F.SilkS")
		)
		(fp_line
			(start 1.943608 -1.549908)
			(end 1.943608 1.549908)
			(stroke
				(width 0.1524)
				(type default)
			)
			(layer "F.SilkS")
		)
		(fp_line
			(start 1.943608 1.549908)
			(end -1.943608 1.549908)
			(stroke
				(width 0.1524)
				(type default)
			)
			(layer "F.SilkS")
		)
		(fp_poly
			(pts
				(xy -2.019808 -1.549908) (xy -1.257808 -1.549908) (xy -1.257808 -1.880108) (xy -2.019808 -1.880108)
			)
			(stroke
				(width 0)
				(type default)
			)
			(fill yes)
			(layer "F.SilkS")
		)
		(fp_line
			(start -1.549908 -1.549908)
			(end 1.549908 -1.549908)
			(stroke
				(width 0.1)
				(type default)
			)
			(layer "F.Fab")
		)
		(fp_line
			(start -1.549908 1.549908)
			(end -1.549908 -1.549908)
			(stroke
				(width 0.1)
				(type default)
			)
			(layer "F.Fab")
		)
		(fp_line
			(start 1.549908 -1.549908)
			(end 1.549908 1.549908)
			(stroke
				(width 0.1)
				(type default)
			)
			(layer "F.Fab")
		)
		(fp_line
			(start 1.549908 1.549908)
			(end -1.549908 1.549908)
			(stroke
				(width 0.1)
				(type default)
			)
			(layer "F.Fab")
		)
		(fp_poly
			(pts
				(xy -2.019808 -1.549908) (xy -1.257808 -1.549908) (xy -1.257808 -1.880108) (xy -2.019808 -1.880108)
			)
			(stroke
				(width 0)
				(type default)
			)
			(fill yes)
			(layer "F.Fab")
		)
		(pad "1" smd rect
			(at -1.500124 -1.249934 270)
			(size 0.2794 0.6096)
			(layers "F.Cu" "F.Mask" "F.Paste")
			(net "P12V_SSD15_R")
		)
		(pad "2" smd rect
			(at -1.500124 -0.750062 270)
			(size 0.2794 0.6096)
			(layers "F.Cu" "F.Mask" "F.Paste")
			(net "P12V_SSD15_R")
		)
		(pad "3" smd rect
			(at -1.500124 -0.249936 270)
			(size 0.2794 0.6096)
			(layers "F.Cu" "F.Mask" "F.Paste")
			(net "P12V_SSD15_R")
		)
		(pad "4" smd rect
			(at -1.500124 0.249936 270)
			(size 0.2794 0.6096)
			(layers "F.Cu" "F.Mask" "F.Paste")
			(net "P12V_SSD15_R")
		)
		(pad "5" smd rect
			(at -1.500124 0.750062 270)
			(size 0.2794 0.6096)
			(layers "F.Cu" "F.Mask" "F.Paste")
			(net "P12V_SSD15_R")
		)
		(pad "6" smd rect
			(at -1.500124 1.249934 270)
			(size 0.2794 0.6096)
			(layers "F.Cu" "F.Mask" "F.Paste")
			(net "GND")
		)
		(pad "7" smd rect
			(at 1.500124 1.249934 270)
			(size 0.2794 0.6096)
			(layers "F.Cu" "F.Mask" "F.Paste")
			(net "P12V_SSD15_SS")
		)
		(pad "8" smd rect
			(at 1.500124 0.750062 270)
			(size 0.2794 0.6096)
			(layers "F.Cu" "F.Mask" "F.Paste")
			(net "PWRGD_P12V_SSD15")
		)
		(pad "9" smd rect
			(at 1.500124 0.249936 270)
			(size 0.2794 0.6096)
			(layers "F.Cu" "F.Mask" "F.Paste")
			(net "P12V_SSD15_OCP")
		)
		(pad "10" smd rect
			(at 1.500124 -0.249936 270)
			(size 0.2794 0.6096)
			(layers "F.Cu" "F.Mask" "F.Paste")
			(net "P5V_AUX")
		)
		(pad "11" smd rect
			(at 1.500124 -0.750062 270)
			(size 0.2794 0.6096)
			(layers "F.Cu" "F.Mask" "F.Paste")
			(net "SSD15_PWR_EN_R")
		)
		(pad "12" smd rect
			(at 1.500124 -1.249934 270)
			(size 0.2794 0.6096)
			(layers "F.Cu" "F.Mask" "F.Paste")
			(net "P12V_AUX")
		)
		(pad "13" smd rect
			(at 0 0)
			(size 1.9812 2.7178)
			(layers "F.Cu" "F.Mask" "F.Paste")
			(net "P12V_AUX")
		)
		(zone
			(layer "F.Cu")
			(hatch none 0.5)
			(connect_pads
				(clearance 0)
			)
			(min_thickness 0.25)
			(keepout
				(tracks not_allowed)
				(vias allowed)
				(pads allowed)
				(copperpour not_allowed)
				(footprints allowed)
			)
			(placement
				(enabled no)
				(sheetname "")
			)
			(fill
				(thermal_gap 0.5)
				(thermal_bridge_width 0.5)
				(island_removal_mode 0)
			)
			(polygon
				(pts
					(xy 450.090032 -55.9435) (xy 450.090032 -55.8165) (xy 450.090032 -52.8447) (xy 450.090032 -52.844192)
					(xy 447.804032 -52.844192) (xy 447.804032 -52.8447) (xy 447.804032 -52.9717) (xy 447.804032 -54.3941)
					(xy 447.905632 -54.3941) (xy 447.905632 -52.9717) (xy 449.988432 -52.9717) (xy 449.988432 -55.8165)
					(xy 447.905632 -55.8165) (xy 447.905632 -54.4195) (xy 447.804032 -54.4195) (xy 447.804032 -55.8165)
					(xy 447.804032 -55.9435) (xy 447.804032 -55.944008) (xy 450.090032 -55.944008)
				)
			)
		)
	)
	(footprint ""
		(layer "F.Cu")
		(at 271.895062 -356.244906 90)
		(property "Reference" "C610"
			(at 0 0 90)
			(layer "F.SilkS")
			(hide yes)
			(effects
				(font
					(size 1.27 1.27)
				)
			)
		)
		(property "Value" ""
			(at 0 0 90)
			(layer "F.Fab")
			(effects
				(font
					(size 1.27 1.27)
				)
			)
		)
		(duplicate_pad_numbers_are_jumpers no)
		(fp_line
			(start 0.299974 -0.150114)
			(end 0.299974 0.150114)
			(stroke
				(width 0.1)
				(type default)
			)
			(layer "F.Fab")
		)
		(fp_line
			(start -0.299974 -0.150114)
			(end 0.299974 -0.150114)
			(stroke
				(width 0.1)
				(type default)
			)
			(layer "F.Fab")
		)
		(fp_line
			(start 0.299974 0.150114)
			(end -0.299974 0.150114)
			(stroke
				(width 0.1)
				(type default)
			)
			(layer "F.Fab")
		)
		(fp_line
			(start -0.299974 0.150114)
			(end -0.299974 -0.150114)
			(stroke
				(width 0.1)
				(type default)
			)
			(layer "F.Fab")
		)
		(pad "1" smd rect
			(at -0.2667 0 90)
			(size 0.3048 0.381)
			(layers "F.Cu" "F.Mask" "F.Paste")
			(net "P5E_PEX2_STN7_TX_DN<114>")
		)
		(pad "2" smd rect
			(at 0.2667 0 90)
			(size 0.3048 0.381)
			(layers "F.Cu" "F.Mask" "F.Paste")
			(net "P5E_PEX2_STN7_TX_C_DN<114>")
		)
	)
	(footprint ""
		(layer "F.Cu")
		(at 243.564918 -312.671714)
		(property "Reference" "PC250"
			(at 0 0 0)
			(layer "F.SilkS")
			(hide yes)
			(effects
				(font
					(size 1.27 1.27)
				)
			)
		)
		(property "Value" ""
			(at 0 0 0)
			(layer "F.Fab")
			(effects
				(font
					(size 1.27 1.27)
				)
			)
		)
		(duplicate_pad_numbers_are_jumpers no)
		(fp_line
			(start -1.524 -0.762)
			(end 1.524 -0.762)
			(stroke
				(width 0.1524)
				(type default)
			)
			(layer "F.SilkS")
		)
		(fp_line
			(start -1.524 0.762)
			(end -1.524 -0.762)
			(stroke
				(width 0.1524)
				(type default)
			)
			(layer "F.SilkS")
		)
		(fp_line
			(start 1.524 -0.762)
			(end 1.524 0.762)
			(stroke
				(width 0.1524)
				(type default)
			)
			(layer "F.SilkS")
		)
		(fp_line
			(start 1.524 0.762)
			(end -1.524 0.762)
			(stroke
				(width 0.1524)
				(type default)
			)
			(layer "F.SilkS")
		)
		(fp_line
			(start -1.1049 -0.724916)
			(end -1.1049 0.724916)
			(stroke
				(width 0.1)
				(type default)
			)
			(layer "F.Fab")
		)
		(fp_line
			(start -1.1049 0.724916)
			(end 1.1049 0.724916)
			(stroke
				(width 0.1)
				(type default)
			)
			(layer "F.Fab")
		)
		(fp_line
			(start 1.1049 -0.724916)
			(end -1.1049 -0.724916)
			(stroke
				(width 0.1)
				(type default)
			)
			(layer "F.Fab")
		)
		(fp_line
			(start 1.1049 0.724916)
			(end 1.1049 -0.724916)
			(stroke
				(width 0.1)
				(type default)
			)
			(layer "F.Fab")
		)
		(pad "1" smd rect
			(at -0.889 0 180)
			(size 1.016 1.27)
			(layers "F.Cu" "F.Mask" "F.Paste")
			(net "SW_P12V_P1V25_PEX2_FLT")
		)
		(pad "2" smd rect
			(at 0.889 0 180)
			(size 1.016 1.27)
			(layers "F.Cu" "F.Mask" "F.Paste")
			(net "GND")
		)
	)
	(footprint ""
		(layer "F.Cu")
		(at 289.634422 -350.098614 90)
		(property "Reference" "C2361"
			(at 0 0 90)
			(layer "F.SilkS")
			(hide yes)
			(effects
				(font
					(size 1.27 1.27)
				)
			)
		)
		(property "Value" ""
			(at 0 0 90)
			(layer "F.Fab")
			(effects
				(font
					(size 1.27 1.27)
				)
			)
		)
		(duplicate_pad_numbers_are_jumpers no)
		(fp_line
			(start 0.299974 -0.150114)
			(end 0.299974 0.150114)
			(stroke
				(width 0.1)
				(type default)
			)
			(layer "F.Fab")
		)
		(fp_line
			(start -0.299974 -0.150114)
			(end 0.299974 -0.150114)
			(stroke
				(width 0.1)
				(type default)
			)
			(layer "F.Fab")
		)
		(fp_line
			(start 0.299974 0.150114)
			(end -0.299974 0.150114)
			(stroke
				(width 0.1)
				(type default)
			)
			(layer "F.Fab")
		)
		(fp_line
			(start -0.299974 0.150114)
			(end -0.299974 -0.150114)
			(stroke
				(width 0.1)
				(type default)
			)
			(layer "F.Fab")
		)
		(pad "1" smd rect
			(at -0.2667 0 90)
			(size 0.3048 0.381)
			(layers "F.Cu" "F.Mask" "F.Paste")
			(net "P5E_PEX2_STN4_TX_DP<69>")
		)
		(pad "2" smd rect
			(at 0.2667 0 90)
			(size 0.3048 0.381)
			(layers "F.Cu" "F.Mask" "F.Paste")
			(net "P5E_PEX2_STN4_TX_C_DP<69>")
		)
	)
	(footprint ""
		(layer "F.Cu")
		(at 220.077792 -254.18542 -90)
		(property "Reference" "C4282"
			(at 0 0 270)
			(layer "F.SilkS")
			(hide yes)
			(effects
				(font
					(size 1.27 1.27)
				)
			)
		)
		(property "Value" ""
			(at 0 0 270)
			(layer "F.Fab")
			(effects
				(font
					(size 1.27 1.27)
				)
			)
		)
		(duplicate_pad_numbers_are_jumpers no)
		(fp_line
			(start -1.2954 0.5842)
			(end -1.2954 -0.5842)
			(stroke
				(width 0.1524)
				(type default)
			)
			(layer "F.SilkS")
		)
		(fp_line
			(start 1.2954 0.5842)
			(end -1.2954 0.5842)
			(stroke
				(width 0.1524)
				(type default)
			)
			(layer "F.SilkS")
		)
		(fp_line
			(start -1.2954 -0.5842)
			(end 1.2954 -0.5842)
			(stroke
				(width 0.1524)
				(type default)
			)
			(layer "F.SilkS")
		)
		(fp_line
			(start 1.2954 -0.5842)
			(end 1.2954 0.5842)
			(stroke
				(width 0.1524)
				(type default)
			)
			(layer "F.SilkS")
		)
		(fp_line
			(start -0.8636 0.4572)
			(end -0.8636 0.4064)
			(stroke
				(width 0.1)
				(type default)
			)
			(layer "F.Fab")
		)
		(fp_line
			(start 0.8636 0.4572)
			(end -0.8636 0.4572)
			(stroke
				(width 0.1)
				(type default)
			)
			(layer "F.Fab")
		)
		(fp_line
			(start -1.1938 0.4064)
			(end -1.1938 -0.4064)
			(stroke
				(width 0.1)
				(type default)
			)
			(layer "F.Fab")
		)
		(fp_line
			(start -0.8636 0.4064)
			(end -1.1938 0.4064)
			(stroke
				(width 0.1)
				(type default)
			)
			(layer "F.Fab")
		)
		(fp_line
			(start 0.8636 0.4064)
			(end 0.8636 0.4572)
			(stroke
				(width 0.1)
				(type default)
			)
			(layer "F.Fab")
		)
		(fp_line
			(start 1.1938 0.4064)
			(end 0.8636 0.4064)
			(stroke
				(width 0.1)
				(type default)
			)
			(layer "F.Fab")
		)
		(fp_line
			(start -1.1938 -0.4064)
			(end -0.8636 -0.4064)
			(stroke
				(width 0.1)
				(type default)
			)
			(layer "F.Fab")
		)
		(fp_line
			(start -0.8636 -0.4064)
			(end -0.8636 -0.4572)
			(stroke
				(width 0.1)
				(type default)
			)
			(layer "F.Fab")
		)
		(fp_line
			(start 0.8636 -0.4064)
			(end 1.1938 -0.4064)
			(stroke
				(width 0.1)
				(type default)
			)
			(layer "F.Fab")
		)
		(fp_line
			(start 1.1938 -0.4064)
			(end 1.1938 0.4064)
			(stroke
				(width 0.1)
				(type default)
			)
			(layer "F.Fab")
		)
		(fp_line
			(start -0.8636 -0.4572)
			(end 0.8636 -0.4572)
			(stroke
				(width 0.1)
				(type default)
			)
			(layer "F.Fab")
		)
		(fp_line
			(start 0.8636 -0.4572)
			(end 0.8636 -0.4064)
			(stroke
				(width 0.1)
				(type default)
			)
			(layer "F.Fab")
		)
		(pad "1" smd rect
			(at -0.7366 0 180)
			(size 0.7112 0.8128)
			(layers "F.Cu" "F.Mask" "F.Paste")
			(net "P1V25_SERDES_VDDPLL_PEX1_C0")
		)
		(pad "2" smd rect
			(at 0.7366 0 180)
			(size 0.7112 0.8128)
			(layers "F.Cu" "F.Mask" "F.Paste")
			(net "GND")
		)
	)
	(footprint ""
		(layer "F.Cu")
		(at 213.868 -228.6 -90)
		(property "Reference" "R6214"
			(at 0 0 270)
			(layer "F.SilkS")
			(hide yes)
			(effects
				(font
					(size 1.27 1.27)
				)
			)
		)
		(property "Value" ""
			(at 0 0 270)
			(layer "F.Fab")
			(effects
				(font
					(size 1.27 1.27)
				)
			)
		)
		(duplicate_pad_numbers_are_jumpers no)
		(fp_line
			(start -0.7874 0.4064)
			(end -0.7874 -0.4064)
			(stroke
				(width 0.1524)
				(type default)
			)
			(layer "F.SilkS")
		)
		(fp_line
			(start 0.7874 0.4064)
			(end -0.7874 0.4064)
			(stroke
				(width 0.1524)
				(type default)
			)
			(layer "F.SilkS")
		)
		(fp_line
			(start -0.7874 -0.4064)
			(end 0.7874 -0.4064)
			(stroke
				(width 0.1524)
				(type default)
			)
			(layer "F.SilkS")
		)
		(fp_line
			(start 0.7874 -0.4064)
			(end 0.7874 0.4064)
			(stroke
				(width 0.1524)
				(type default)
			)
			(layer "F.SilkS")
		)
		(fp_line
			(start -0.67945 0.3048)
			(end -0.67945 -0.305054)
			(stroke
				(width 0.1)
				(type default)
			)
			(layer "F.Fab")
		)
		(fp_line
			(start -0.12065 0.3048)
			(end -0.67945 0.3048)
			(stroke
				(width 0.1)
				(type default)
			)
			(layer "F.Fab")
		)
		(fp_line
			(start 0.120396 0.3048)
			(end 0.120396 0.2794)
			(stroke
				(width 0.1)
				(type default)
			)
			(layer "F.Fab")
		)
		(fp_line
			(start 0.67945 0.3048)
			(end 0.120396 0.3048)
			(stroke
				(width 0.1)
				(type default)
			)
			(layer "F.Fab")
		)
		(fp_line
			(start -0.12065 0.2794)
			(end -0.12065 0.3048)
			(stroke
				(width 0.1)
				(type default)
			)
			(layer "F.Fab")
		)
		(fp_line
			(start 0.120396 0.2794)
			(end -0.12065 0.2794)
			(stroke
				(width 0.1)
				(type default)
			)
			(layer "F.Fab")
		)
		(fp_line
			(start -0.12065 -0.2794)
			(end 0.12065 -0.2794)
			(stroke
				(width 0.1)
				(type default)
			)
			(layer "F.Fab")
		)
		(fp_line
			(start 0.12065 -0.2794)
			(end 0.12065 -0.3048)
			(stroke
				(width 0.1)
				(type default)
			)
			(layer "F.Fab")
		)
		(fp_line
			(start 0.12065 -0.3048)
			(end 0.67945 -0.3048)
			(stroke
				(width 0.1)
				(type default)
			)
			(layer "F.Fab")
		)
		(fp_line
			(start 0.67945 -0.3048)
			(end 0.67945 0.3048)
			(stroke
				(width 0.1)
				(type default)
			)
			(layer "F.Fab")
		)
		(fp_line
			(start -0.67945 -0.305054)
			(end -0.12065 -0.305054)
			(stroke
				(width 0.1)
				(type default)
			)
			(layer "F.Fab")
		)
		(fp_line
			(start -0.12065 -0.305054)
			(end -0.12065 -0.2794)
			(stroke
				(width 0.1)
				(type default)
			)
			(layer "F.Fab")
		)
		(pad "1" smd circle
			(at -0.40005 0 270)
			(size 0 0)
			(layers "F.Cu" "F.Mask" "F.Paste")
			(net "PRSNT_DBV2_SLIMSAS_R")
		)
		(pad "2" smd circle
			(at 0.40005 0 270)
			(size 0 0)
			(layers "F.Cu" "F.Mask" "F.Paste")
			(net "P3V3_AUX")
		)
	)
	(footprint ""
		(layer "F.Cu")
		(at 381.41148 -261.434834)
		(property "Reference" "L139"
			(at 0 0 0)
			(layer "F.SilkS")
			(hide yes)
			(effects
				(font
					(size 1.27 1.27)
				)
			)
		)
		(property "Value" ""
			(at 0 0 0)
			(layer "F.Fab")
			(effects
				(font
					(size 1.27 1.27)
				)
			)
		)
		(duplicate_pad_numbers_are_jumpers no)
		(fp_line
			(start -1.63576 -0.8128)
			(end -1.63576 0.8128)
			(stroke
				(width 0.1524)
				(type default)
			)
			(layer "F.SilkS")
		)
		(fp_line
			(start -1.63576 -0.8128)
			(end 1.63576 -0.8128)
			(stroke
				(width 0.1524)
				(type default)
			)
			(layer "F.SilkS")
		)
		(fp_line
			(start 1.63576 -0.8128)
			(end 1.63576 0.8128)
			(stroke
				(width 0.1524)
				(type default)
			)
			(layer "F.SilkS")
		)
		(fp_line
			(start 1.63576 0.8128)
			(end -1.63576 0.8128)
			(stroke
				(width 0.1524)
				(type default)
			)
			(layer "F.SilkS")
		)
		(fp_line
			(start -1.56083 -0.738632)
			(end -1.56083 0.7366)
			(stroke
				(width 0.1)
				(type default)
			)
			(layer "F.Fab")
		)
		(fp_line
			(start -1.56083 0.7366)
			(end -1.524 0.7366)
			(stroke
				(width 0.1)
				(type default)
			)
			(layer "F.Fab")
		)
		(fp_line
			(start -1.524 0.7366)
			(end 1.524 0.7366)
			(stroke
				(width 0.1)
				(type default)
			)
			(layer "F.Fab")
		)
		(fp_line
			(start 1.524 0.7366)
			(end 1.560576 0.7366)
			(stroke
				(width 0.1)
				(type default)
			)
			(layer "F.Fab")
		)
		(fp_line
			(start 1.560576 -0.738632)
			(end -1.56083 -0.738632)
			(stroke
				(width 0.1)
				(type default)
			)
			(layer "F.Fab")
		)
		(fp_line
			(start 1.560576 0.7366)
			(end 1.560576 -0.738632)
			(stroke
				(width 0.1)
				(type default)
			)
			(layer "F.Fab")
		)
		(pad "1" smd rect
			(at -0.94996 0 180)
			(size 1.1176 1.3716)
			(layers "F.Cu" "F.Mask" "F.Paste")
			(net "P1V8_PLL0_PEX3")
		)
		(pad "2" smd rect
			(at 0.94996 0 180)
			(size 1.1176 1.3716)
			(layers "F.Cu" "F.Mask" "F.Paste")
			(net "PCEPLL3_VDDA18_PEX3")
		)
	)
)
